(kicad_pcb
	(version 20260206)
	(generator "pcbnew")
	(generator_version "10.0")
	(general
		(thickness 1.6)
		(legacy_teardrops no)
	)
	(paper "A4")
	(title_block
		(title "Wiwynn_Tioga_Pass_MB.brd")
		(comment 1 "Tioga Pass / footprints 1157-1163 of 4770")
	)
	(layers
		(0 "F.Cu" signal "TOP")
		(4 "In1.Cu" signal "L2GND")
		(6 "In2.Cu" signal "L3")
		(8 "In3.Cu" signal "L4GND")
		(10 "In4.Cu" signal "L5")
		(12 "In5.Cu" signal "L6GND")
		(14 "In6.Cu" signal "L7VCC")
		(16 "In7.Cu" signal "L8VCC")
		(18 "In8.Cu" signal "L9GND")
		(20 "In9.Cu" signal "L10")
		(22 "In10.Cu" signal "L11GND")
		(24 "In11.Cu" signal "L12")
		(26 "In12.Cu" signal "L13GND")
		(2 "B.Cu" signal "BOTTOM")
		(9 "F.Adhes" user "F.Adhesive")
		(11 "B.Adhes" user "B.Adhesive")
		(13 "F.Paste" user "Package Geometry/Pastemask Top")
		(15 "B.Paste" user "Package Geometry/Pastemask Bottom")
		(5 "F.SilkS" user "Ref Des/Silkscreen Top")
		(7 "B.SilkS" user "Ref Des/Silkscreen Bottom")
		(1 "F.Mask" user "Board Geometry/Soldermask Top")
		(3 "B.Mask" user "Board Geometry/Soldermask Bottom")
		(17 "Dwgs.User" user "User.Drawings")
		(19 "Cmts.User" user "User.Comments")
		(21 "Eco1.User" user "User.Eco1")
		(23 "Eco2.User" user "User.Eco2")
		(25 "Edge.Cuts" user "Board Geometry/Outline")
		(27 "Margin" user)
		(31 "F.CrtYd" user "Package Geometry/Place Bound Top")
		(29 "B.CrtYd" user "Package Geometry/Place Bound Bottom")
		(35 "F.Fab" user "Ref Des/Assembly Top")
		(33 "B.Fab" user "Ref Des/Assembly Bottom")
	)
	(footprint ""
		(layer "F.Cu")
		(at 466.5345 -20.6502 90)
		(property "Reference" "R8F9"
			(at 0 0 90)
			(layer "F.SilkS")
			(hide yes)
			(effects
				(font
					(size 1.27 1.27)
				)
			)
		)
		(property "Value" ""
			(at 0 0 90)
			(layer "F.Fab")
			(effects
				(font
					(size 1.27 1.27)
				)
			)
		)
		(duplicate_pad_numbers_are_jumpers no)
		(fp_rect
			(start -0.2794 -0.1016)
			(end 0.2794 0.9906)
			(stroke
				(width 0)
				(type default)
			)
			(fill no)
			(layer "F.CrtYd")
		)
		(fp_line
			(start 0.2794 -0.1016)
			(end -0.2794 -0.1016)
			(stroke
				(width 0.1)
				(type default)
			)
			(layer "F.Fab")
		)
		(fp_line
			(start -0.2794 -0.1016)
			(end -0.2794 0.9906)
			(stroke
				(width 0.1)
				(type default)
			)
			(layer "F.Fab")
		)
		(fp_line
			(start 0.2794 0.9906)
			(end 0.2794 -0.1016)
			(stroke
				(width 0.1)
				(type default)
			)
			(layer "F.Fab")
		)
		(fp_line
			(start -0.2794 0.9906)
			(end 0.2794 0.9906)
			(stroke
				(width 0.1)
				(type default)
			)
			(layer "F.Fab")
		)
		(pad "1" smd rect
			(at 0 0 90)
			(size 0.508 0.508)
			(layers "F.Cu" "F.Mask" "F.Paste")
			(net "VR_P3V3_STBY_OCSELECT")
		)
		(pad "2" smd rect
			(at 0 0.889 90)
			(size 0.508 0.508)
			(layers "F.Cu" "F.Mask" "F.Paste")
			(net "AGND_P3V3_STBY")
		)
		(zone
			(layer "F.Cu")
			(hatch none 0.5)
			(connect_pads
				(clearance 0)
			)
			(min_thickness 0.25)
			(keepout
				(tracks allowed)
				(vias not_allowed)
				(pads allowed)
				(copperpour not_allowed)
				(footprints allowed)
			)
			(placement
				(enabled no)
				(sheetname "")
			)
			(fill
				(thermal_gap 0.5)
				(thermal_bridge_width 0.5)
				(island_removal_mode 0)
			)
			(polygon
				(pts
					(xy 466.7885 -20.3962) (xy 467.1695 -20.3962) (xy 467.1695 -20.9042) (xy 466.7885 -20.9042)
				)
			)
		)
		(zone
			(layer "F.Cu")
			(hatch none 0.5)
			(connect_pads
				(clearance 0)
			)
			(min_thickness 0.25)
			(keepout
				(tracks not_allowed)
				(vias allowed)
				(pads allowed)
				(copperpour not_allowed)
				(footprints allowed)
			)
			(placement
				(enabled no)
				(sheetname "")
			)
			(fill
				(thermal_gap 0.5)
				(thermal_bridge_width 0.5)
				(island_removal_mode 0)
			)
			(polygon
				(pts
					(xy 466.7885 -20.3962) (xy 467.1695 -20.3962) (xy 467.1695 -20.9042) (xy 466.7885 -20.9042)
				)
			)
		)
	)
	(footprint ""
		(layer "F.Cu")
		(at 53.80228 -165.01618 90)
		(property "Reference" "T1D2"
			(at 0 0 90)
			(layer "F.SilkS")
			(hide yes)
			(effects
				(font
					(size 1.27 1.27)
				)
			)
		)
		(property "Value" "*"
			(at -3.4036 -4.46405 90)
			(unlocked yes)
			(layer "F.Fab")
			(hide yes)
			(effects
				(font
					(size 0.889 0.889)
					(thickness 0.1524)
				)
			)
		)
		(property "Device Type" "TEST-PAD-12P-1-GP-U_DISCRET-GBA"
			(at -3.4036 -5.98805 90)
			(unlocked yes)
			(layer "F.Fab")
			(hide yes)
			(effects
				(font
					(size 0.889 0.889)
					(thickness 0.1524)
				)
			)
		)
		(duplicate_pad_numbers_are_jumpers no)
		(fp_line
			(start 2.3622 -4.826)
			(end 2.3622 3.4798)
			(stroke
				(width 0.1524)
				(type default)
			)
			(layer "F.SilkS")
		)
		(fp_line
			(start -2.3876 -4.826)
			(end 2.3622 -4.826)
			(stroke
				(width 0.1524)
				(type default)
			)
			(layer "F.SilkS")
		)
		(fp_line
			(start 2.3622 3.4798)
			(end -2.3876 3.4798)
			(stroke
				(width 0.1524)
				(type default)
			)
			(layer "F.SilkS")
		)
		(fp_line
			(start -2.3876 3.4798)
			(end -2.3876 -4.826)
			(stroke
				(width 0.1524)
				(type default)
			)
			(layer "F.SilkS")
		)
		(fp_rect
			(start -2.6416 3.7338)
			(end 2.6162 -5.08)
			(stroke
				(width 0)
				(type default)
			)
			(fill no)
			(layer "F.CrtYd")
		)
		(fp_rect
			(start -2.6416 3.7338)
			(end 2.6162 -5.08)
			(stroke
				(width 0)
				(type default)
			)
			(fill no)
			(layer "F.Fab")
		)
		(pad "1" smd circle
			(at 0.496824 -1.301496 90)
			(size 0.6604 0.6604)
			(layers "F.Cu" "F.Mask" "F.Paste")
			(net "L1_85OHM_5INCH_DN")
		)
		(pad "2" smd circle
			(at -0.503936 -1.301496 90)
			(size 0.6604 0.6604)
			(layers "F.Cu" "F.Mask" "F.Paste")
			(net "L1_85OHM_5INCH_DP")
		)
		(pad "3" smd custom
			(at -0.00889 0.370078 90)
			(size 0.74295 0.74295)
			(layers "F.Cu" "F.Mask" "F.Paste")
			(net "GND")
			(options
				(clearance outline)
				(anchor circle)
			)
			(primitives
				(gr_poly
					(pts
						(xy -2.1209 1.4859) (xy 2.1209 1.4859) (xy 2.1209 -1.4859) (xy 1.08585 -1.4859) (xy 1.08585 -0.4699)
						(xy -1.08585 -0.4699) (xy -1.08585 -1.4859) (xy -2.1209 -1.4859)
					)
					(width 0)
					(fill yes)
				)
			)
		)
		(pad "4" thru_hole circle
			(at 1.266444 -3.851656 90)
			(size 1.4478 1.4478)
			(drill 1.0414)
			(layers "*.Cu" "*.Mask")
			(remove_unused_layers no)
			(net "GND")
			(clearance 0.1524)
			(thermal_gap 0.1524)
		)
		(pad "5" thru_hole circle
			(at -1.273556 -3.851656 90)
			(size 1.4478 1.4478)
			(drill 1.0414)
			(layers "*.Cu" "*.Mask")
			(remove_unused_layers no)
			(net "GND")
			(clearance 0.1524)
			(thermal_gap 0.1524)
		)
		(pad "6" thru_hole circle
			(at 1.266444 2.498344 90)
			(size 1.4478 1.4478)
			(drill 1.0414)
			(layers "*.Cu" "*.Mask")
			(remove_unused_layers no)
			(net "GND")
			(clearance 0.1524)
			(thermal_gap 0.1524)
		)
		(pad "7" thru_hole circle
			(at -1.273556 2.498344 90)
			(size 1.4478 1.4478)
			(drill 1.0414)
			(layers "*.Cu" "*.Mask")
			(remove_unused_layers no)
			(net "GND")
			(clearance 0.1524)
			(thermal_gap 0.1524)
		)
		(pad "8" thru_hole circle
			(at 1.27 -0.4572 90)
			(size 0.7112 0.7112)
			(drill 0.4064)
			(layers "*.Cu" "*.Mask")
			(remove_unused_layers no)
			(net "GND")
			(clearance 0.1016)
			(thermal_gap 0.1016)
		)
		(pad "9" thru_hole circle
			(at 1.27 0.762 90)
			(size 0.7112 0.7112)
			(drill 0.4064)
			(layers "*.Cu" "*.Mask")
			(remove_unused_layers no)
			(net "GND")
			(clearance 0.1016)
			(thermal_gap 0.1016)
		)
		(pad "10" thru_hole circle
			(at -0.0254 0.762 90)
			(size 0.7112 0.7112)
			(drill 0.4064)
			(layers "*.Cu" "*.Mask")
			(remove_unused_layers no)
			(net "GND")
			(clearance 0.1016)
			(thermal_gap 0.1016)
		)
		(pad "11" thru_hole circle
			(at -1.27 0.762 90)
			(size 0.7112 0.7112)
			(drill 0.4064)
			(layers "*.Cu" "*.Mask")
			(remove_unused_layers no)
			(net "GND")
			(clearance 0.1016)
			(thermal_gap 0.1016)
		)
		(pad "12" thru_hole circle
			(at -1.27 -0.4572 90)
			(size 0.7112 0.7112)
			(drill 0.4064)
			(layers "*.Cu" "*.Mask")
			(remove_unused_layers no)
			(net "GND")
			(clearance 0.1016)
			(thermal_gap 0.1016)
		)
	)
	(footprint ""
		(layer "F.Cu")
		(at 39.0906 -52.9082 -90)
		(property "Reference" "CT23"
			(at -0.8382 -0.67818 270)
			(unlocked yes)
			(layer "F.SilkS")
			(effects
				(font
					(size 0.4064 0.254)
					(thickness 0.1524)
				)
				(justify left)
			)
		)
		(property "Value" ""
			(at 0 0 270)
			(layer "F.Fab")
			(effects
				(font
					(size 1.27 1.27)
				)
			)
		)
		(duplicate_pad_numbers_are_jumpers no)
		(fp_poly
			(pts
				(xy 0.3048 -0.1016) (xy 0.3048 0.9906) (xy -0.3048 0.9906) (xy -0.3048 -0.1016)
			)
			(stroke
				(width 0)
				(type default)
			)
			(fill no)
			(layer "F.CrtYd")
		)
		(fp_line
			(start -0.3048 0.9906)
			(end 0.3048 0.9906)
			(stroke
				(width 0.1)
				(type default)
			)
			(layer "F.Fab")
		)
		(fp_line
			(start 0.3048 0.9906)
			(end 0.3048 -0.1016)
			(stroke
				(width 0.1)
				(type default)
			)
			(layer "F.Fab")
		)
		(fp_line
			(start -0.3048 -0.1016)
			(end -0.3048 0.9906)
			(stroke
				(width 0.1)
				(type default)
			)
			(layer "F.Fab")
		)
		(fp_line
			(start 0.3048 -0.1016)
			(end -0.3048 -0.1016)
			(stroke
				(width 0.1)
				(type default)
			)
			(layer "F.Fab")
		)
		(pad "1" smd rect
			(at 0 0 270)
			(size 0.508 0.508)
			(layers "F.Cu" "F.Mask" "F.Paste")
			(net "VR_PVCCIN_CPU1_PHASE1")
		)
		(pad "2" smd rect
			(at 0 0.889 270)
			(size 0.508 0.508)
			(layers "F.Cu" "F.Mask" "F.Paste")
			(net "VR_PVCCIN_CPU1_PHASE1_RC")
		)
		(zone
			(layer "F.Cu")
			(hatch none 0.5)
			(connect_pads
				(clearance 0)
			)
			(min_thickness 0.25)
			(keepout
				(tracks not_allowed)
				(vias allowed)
				(pads allowed)
				(copperpour not_allowed)
				(footprints allowed)
			)
			(placement
				(enabled no)
				(sheetname "")
			)
			(fill
				(thermal_gap 0.5)
				(thermal_bridge_width 0.5)
				(island_removal_mode 0)
			)
			(polygon
				(pts
					(xy 38.4556 -53.1622) (xy 38.4556 -52.6542) (xy 38.8366 -52.6542) (xy 38.8366 -53.1622)
				)
			)
		)
		(zone
			(layer "F.Cu")
			(hatch none 0.5)
			(connect_pads
				(clearance 0)
			)
			(min_thickness 0.25)
			(keepout
				(tracks allowed)
				(vias not_allowed)
				(pads allowed)
				(copperpour not_allowed)
				(footprints allowed)
			)
			(placement
				(enabled no)
				(sheetname "")
			)
			(fill
				(thermal_gap 0.5)
				(thermal_bridge_width 0.5)
				(island_removal_mode 0)
			)
			(polygon
				(pts
					(xy 38.8366 -53.1622) (xy 38.8366 -52.6542) (xy 38.4556 -52.6542) (xy 38.4556 -53.1622)
				)
			)
		)
	)
	(footprint ""
		(layer "F.Cu")
		(at 465.5947 -24.8539 -90)
		(property "Reference" "R8E38"
			(at 0 0 270)
			(layer "F.SilkS")
			(hide yes)
			(effects
				(font
					(size 1.27 1.27)
				)
			)
		)
		(property "Value" ""
			(at 0 0 270)
			(layer "F.Fab")
			(effects
				(font
					(size 1.27 1.27)
				)
			)
		)
		(duplicate_pad_numbers_are_jumpers no)
		(fp_rect
			(start 0.2794 0.9906)
			(end -0.2794 -0.1016)
			(stroke
				(width 0)
				(type default)
			)
			(fill no)
			(layer "F.CrtYd")
		)
		(fp_line
			(start -0.2794 0.9906)
			(end 0.2794 0.9906)
			(stroke
				(width 0.1)
				(type default)
			)
			(layer "F.Fab")
		)
		(fp_line
			(start 0.2794 0.9906)
			(end 0.2794 -0.1016)
			(stroke
				(width 0.1)
				(type default)
			)
			(layer "F.Fab")
		)
		(fp_line
			(start -0.2794 -0.1016)
			(end -0.2794 0.9906)
			(stroke
				(width 0.1)
				(type default)
			)
			(layer "F.Fab")
		)
		(fp_line
			(start 0.2794 -0.1016)
			(end -0.2794 -0.1016)
			(stroke
				(width 0.1)
				(type default)
			)
			(layer "F.Fab")
		)
		(pad "1" smd rect
			(at 0 0 270)
			(size 0.508 0.508)
			(layers "F.Cu" "F.Mask" "F.Paste")
			(net "VSENSE_RGND_P3V3_STBY")
		)
		(pad "2" smd rect
			(at 0 0.889 270)
			(size 0.508 0.508)
			(layers "F.Cu" "F.Mask" "F.Paste")
			(net "AGND_P3V3_STBY")
		)
		(zone
			(layer "F.Cu")
			(hatch none 0.5)
			(connect_pads
				(clearance 0)
			)
			(min_thickness 0.25)
			(keepout
				(tracks not_allowed)
				(vias allowed)
				(pads allowed)
				(copperpour not_allowed)
				(footprints allowed)
			)
			(placement
				(enabled no)
				(sheetname "")
			)
			(fill
				(thermal_gap 0.5)
				(thermal_bridge_width 0.5)
				(island_removal_mode 0)
			)
			(polygon
				(pts
					(xy 464.9597 -24.5999) (xy 465.3407 -24.5999) (xy 465.3407 -25.1079) (xy 464.9597 -25.1079)
				)
			)
		)
		(zone
			(layer "F.Cu")
			(hatch none 0.5)
			(connect_pads
				(clearance 0)
			)
			(min_thickness 0.25)
			(keepout
				(tracks allowed)
				(vias not_allowed)
				(pads allowed)
				(copperpour not_allowed)
				(footprints allowed)
			)
			(placement
				(enabled no)
				(sheetname "")
			)
			(fill
				(thermal_gap 0.5)
				(thermal_bridge_width 0.5)
				(island_removal_mode 0)
			)
			(polygon
				(pts
					(xy 464.9597 -24.5999) (xy 465.3407 -24.5999) (xy 465.3407 -25.1079) (xy 464.9597 -25.1079)
				)
			)
		)
	)
	(footprint ""
		(layer "F.Cu")
		(at 387.754876 -158.152084 -90)
		(property "Reference" "RT46"
			(at 1.01473 0.656336 180)
			(unlocked yes)
			(layer "F.SilkS")
			(effects
				(font
					(size 0.4064 0.254)
					(thickness 0.1524)
				)
			)
		)
		(property "Value" ""
			(at 0 0 270)
			(layer "F.Fab")
			(effects
				(font
					(size 1.27 1.27)
				)
			)
		)
		(duplicate_pad_numbers_are_jumpers no)
		(fp_poly
			(pts
				(xy -0.4953 -0.2032) (xy 0.4953 -0.2032) (xy 0.4953 1.6002) (xy -0.4953 1.6002)
			)
			(stroke
				(width 0)
				(type default)
			)
			(fill no)
			(layer "F.CrtYd")
		)
		(fp_line
			(start -0.4953 1.6002)
			(end -0.4953 -0.2032)
			(stroke
				(width 0.1)
				(type default)
			)
			(layer "F.Fab")
		)
		(fp_line
			(start 0.4953 1.6002)
			(end -0.4953 1.6002)
			(stroke
				(width 0.1)
				(type default)
			)
			(layer "F.Fab")
		)
		(fp_line
			(start -0.4953 -0.2032)
			(end 0.4953 -0.2032)
			(stroke
				(width 0.1)
				(type default)
			)
			(layer "F.Fab")
		)
		(fp_line
			(start 0.4953 -0.2032)
			(end 0.4953 1.6002)
			(stroke
				(width 0.1)
				(type default)
			)
			(layer "F.Fab")
		)
		(pad "1" smd rect
			(at 0 0 270)
			(size 0.762 0.889)
			(layers "F.Cu" "F.Mask" "F.Paste")
			(net "VR_P1V05_PCH_STBY_PH1_BOOT")
		)
		(pad "2" smd rect
			(at 0 1.397 270)
			(size 0.762 0.889)
			(layers "F.Cu" "F.Mask" "F.Paste")
			(net "VR_P1V05_PCH_STBY_PH1_BOOT_R")
		)
		(zone
			(layer "F.Cu")
			(hatch none 0.5)
			(connect_pads
				(clearance 0)
			)
			(min_thickness 0.25)
			(keepout
				(tracks not_allowed)
				(vias allowed)
				(pads allowed)
				(copperpour not_allowed)
				(footprints allowed)
			)
			(placement
				(enabled no)
				(sheetname "")
			)
			(fill
				(thermal_gap 0.5)
				(thermal_bridge_width 0.5)
				(island_removal_mode 0)
			)
			(polygon
				(pts
					(xy 386.802376 -158.533084) (xy 386.802376 -157.771084) (xy 387.310376 -157.771084) (xy 387.310376 -158.533084)
				)
			)
		)
		(zone
			(layer "F.Cu")
			(hatch none 0.5)
			(connect_pads
				(clearance 0)
			)
			(min_thickness 0.25)
			(keepout
				(tracks allowed)
				(vias not_allowed)
				(pads allowed)
				(copperpour not_allowed)
				(footprints allowed)
			)
			(placement
				(enabled no)
				(sheetname "")
			)
			(fill
				(thermal_gap 0.5)
				(thermal_bridge_width 0.5)
				(island_removal_mode 0)
			)
			(polygon
				(pts
					(xy 386.802376 -157.771084) (xy 387.310376 -157.771084) (xy 387.310376 -158.533084) (xy 386.802376 -158.533084)
				)
			)
		)
	)
	(footprint ""
		(layer "F.Cu")
		(at 173.5836 -4.5466 90)
		(property "Reference" "C4G13"
			(at 0 0 90)
			(layer "F.SilkS")
			(hide yes)
			(effects
				(font
					(size 1.27 1.27)
				)
			)
		)
		(property "Value" ""
			(at 0 0 90)
			(layer "F.Fab")
			(effects
				(font
					(size 1.27 1.27)
				)
			)
		)
		(duplicate_pad_numbers_are_jumpers no)
		(fp_rect
			(start 0.3048 0.9906)
			(end -0.3048 -0.1016)
			(stroke
				(width 0)
				(type default)
			)
			(fill no)
			(layer "F.CrtYd")
		)
		(fp_line
			(start 0.3048 -0.1016)
			(end -0.3048 -0.1016)
			(stroke
				(width 0.1)
				(type default)
			)
			(layer "F.Fab")
		)
		(fp_line
			(start -0.3048 -0.1016)
			(end -0.3048 0.9906)
			(stroke
				(width 0.1)
				(type default)
			)
			(layer "F.Fab")
		)
		(fp_line
			(start 0.3048 0.9906)
			(end 0.3048 -0.1016)
			(stroke
				(width 0.1)
				(type default)
			)
			(layer "F.Fab")
		)
		(fp_line
			(start -0.3048 0.9906)
			(end 0.3048 0.9906)
			(stroke
				(width 0.1)
				(type default)
			)
			(layer "F.Fab")
		)
		(pad "1" smd rect
			(at 0 0 90)
			(size 0.508 0.508)
			(layers "F.Cu" "F.Mask" "F.Paste")
			(net "PWRGD_PVTT_GHJ_CPU1_R")
		)
		(pad "2" smd rect
			(at 0 0.889 90)
			(size 0.508 0.508)
			(layers "F.Cu" "F.Mask" "F.Paste")
			(net "GND")
		)
		(zone
			(layer "F.Cu")
			(hatch none 0.5)
			(connect_pads
				(clearance 0)
			)
			(min_thickness 0.25)
			(keepout
				(tracks allowed)
				(vias not_allowed)
				(pads allowed)
				(copperpour not_allowed)
				(footprints allowed)
			)
			(placement
				(enabled no)
				(sheetname "")
			)
			(fill
				(thermal_gap 0.5)
				(thermal_bridge_width 0.5)
				(island_removal_mode 0)
			)
			(polygon
				(pts
					(xy 174.2186 -4.8006) (xy 173.8376 -4.8006) (xy 173.8376 -4.2926) (xy 174.2186 -4.2926)
				)
			)
		)
		(zone
			(layer "F.Cu")
			(hatch none 0.5)
			(connect_pads
				(clearance 0)
			)
			(min_thickness 0.25)
			(keepout
				(tracks not_allowed)
				(vias allowed)
				(pads allowed)
				(copperpour not_allowed)
				(footprints allowed)
			)
			(placement
				(enabled no)
				(sheetname "")
			)
			(fill
				(thermal_gap 0.5)
				(thermal_bridge_width 0.5)
				(island_removal_mode 0)
			)
			(polygon
				(pts
					(xy 174.2186 -4.8006) (xy 173.8376 -4.8006) (xy 173.8376 -4.2926) (xy 174.2186 -4.2926)
				)
			)
		)
	)
	(footprint ""
		(layer "F.Cu")
		(at 405.1935 -118.237 90)
		(property "Reference" "C8B14"
			(at 0 0 90)
			(layer "F.SilkS")
			(hide yes)
			(effects
				(font
					(size 1.27 1.27)
				)
			)
		)
		(property "Value" ""
			(at 0 0 90)
			(layer "F.Fab")
			(effects
				(font
					(size 1.27 1.27)
				)
			)
		)
		(duplicate_pad_numbers_are_jumpers no)
		(fp_poly
			(pts
				(xy -0.4953 -0.2032) (xy 0.4953 -0.2032) (xy 0.4953 1.6002) (xy -0.4953 1.6002)
			)
			(stroke
				(width 0)
				(type default)
			)
			(fill no)
			(layer "F.CrtYd")
		)
		(fp_line
			(start 0.4953 -0.2032)
			(end 0.4953 1.6002)
			(stroke
				(width 0.1)
				(type default)
			)
			(layer "F.Fab")
		)
		(fp_line
			(start -0.4953 -0.2032)
			(end 0.4953 -0.2032)
			(stroke
				(width 0.1)
				(type default)
			)
			(layer "F.Fab")
		)
		(fp_line
			(start 0.4953 1.6002)
			(end -0.4953 1.6002)
			(stroke
				(width 0.1)
				(type default)
			)
			(layer "F.Fab")
		)
		(fp_line
			(start -0.4953 1.6002)
			(end -0.4953 -0.2032)
			(stroke
				(width 0.1)
				(type default)
			)
			(layer "F.Fab")
		)
		(pad "1" smd rect
			(at 0 0 90)
			(size 0.762 0.889)
			(layers "F.Cu" "F.Mask" "F.Paste")
			(net "P1V05_PCH_STBY")
		)
		(pad "2" smd rect
			(at 0 1.397 90)
			(size 0.762 0.889)
			(layers "F.Cu" "F.Mask" "F.Paste")
			(net "GND")
		)
		(zone
			(layer "F.Cu")
			(hatch none 0.5)
			(connect_pads
				(clearance 0)
			)
			(min_thickness 0.25)
			(keepout
				(tracks not_allowed)
				(vias allowed)
				(pads allowed)
				(copperpour not_allowed)
				(footprints allowed)
			)
			(placement
				(enabled no)
				(sheetname "")
			)
			(fill
				(thermal_gap 0.5)
				(thermal_bridge_width 0.5)
				(island_removal_mode 0)
			)
			(polygon
				(pts
					(xy 405.638 -117.856) (xy 405.638 -118.618) (xy 406.146 -118.618) (xy 406.146 -117.856)
				)
			)
		)
	)
)
